(kicad_pcb
	(version 20260206)
	(generator "pcbnew")
	(generator_version "10.0")
	(general
		(thickness 1.6)
		(legacy_teardrops no)
	)
	(paper "A4")
	(title_block
		(title "dpb — 14545-sa.0730WZS0815.brd")
		(comment 1 "Honey Badger (Wiwynn) / footprints 857-863 of 1066")
	)
	(layers
		(0 "F.Cu" signal "TOP")
		(4 "In1.Cu" signal "L2GND")
		(6 "In2.Cu" signal "L3")
		(8 "In3.Cu" signal "L4VCC")
		(10 "In4.Cu" signal "L5VCC")
		(12 "In5.Cu" signal "L6")
		(14 "In6.Cu" signal "L7GND")
		(2 "B.Cu" signal "BOTTOM")
		(9 "F.Adhes" user "F.Adhesive")
		(11 "B.Adhes" user "B.Adhesive")
		(13 "F.Paste" user "Package Geometry/Pastemask Top")
		(15 "B.Paste" user "Package Geometry/Pastemask Bottom")
		(5 "F.SilkS" user "Ref Des/Silkscreen Top")
		(7 "B.SilkS" user "Ref Des/Silkscreen Bottom")
		(1 "F.Mask" user "Board Geometry/Soldermask Top")
		(3 "B.Mask" user "Board Geometry/Soldermask Bottom")
		(17 "Dwgs.User" user "User.Drawings")
		(19 "Cmts.User" user "User.Comments")
		(21 "Eco1.User" user "User.Eco1")
		(23 "Eco2.User" user "User.Eco2")
		(25 "Edge.Cuts" user "Board Geometry/Outline")
		(27 "Margin" user)
		(31 "F.CrtYd" user "Package Geometry/Place Bound Top")
		(29 "B.CrtYd" user "Package Geometry/Place Bound Bottom")
		(35 "F.Fab" user "Ref Des/Assembly Top")
		(33 "B.Fab" user "Ref Des/Assembly Bottom")
	)
	(footprint ""
		(layer "F.Cu")
		(at 224.789746 -143.5227 90)
		(property "Reference" "R145"
			(at 0 0 90)
			(layer "F.SilkS")
			(hide yes)
			(effects
				(font
					(size 1.27 1.27)
				)
			)
		)
		(property "Value" "330R2F-GP"
			(at 0.064008 -3.993896 90)
			(unlocked yes)
			(layer "F.Fab")
			(hide yes)
			(effects
				(font
					(size 1.016 1.016)
					(thickness 0.1524)
				)
			)
		)
		(property "Device Type" "R402H16"
			(at 0.064008 -5.517896 90)
			(unlocked yes)
			(layer "F.Fab")
			(hide yes)
			(effects
				(font
					(size 1.016 1.016)
					(thickness 0.1524)
				)
			)
		)
		(duplicate_pad_numbers_are_jumpers no)
		(fp_line
			(start 0.508 -0.9398)
			(end -0.508 -0.9398)
			(stroke
				(width 0.1524)
				(type default)
			)
			(layer "F.SilkS")
		)
		(fp_line
			(start -0.508 -0.9398)
			(end -0.508 0.9398)
			(stroke
				(width 0.1524)
				(type default)
			)
			(layer "F.SilkS")
		)
		(fp_rect
			(start -0.508 0.9398)
			(end 0.508 -0.9398)
			(stroke
				(width 0)
				(type default)
			)
			(fill no)
			(layer "F.CrtYd")
		)
		(fp_rect
			(start -0.508 0.9398)
			(end 0.508 -0.9398)
			(stroke
				(width 0)
				(type default)
			)
			(fill no)
			(layer "F.Fab")
		)
		(pad "1" smd custom
			(at 0 -0.4445 90)
			(size 0.1397 0.1397)
			(layers "F.Cu" "F.Mask" "F.Paste")
			(net "P3V3_HDD3_LED")
			(options
				(clearance outline)
				(anchor circle)
			)
			(primitives
				(gr_poly
					(pts
						(arc
							(start -0.1778 -0.2794)
							(mid -0.249642 -0.249642)
							(end -0.2794 -0.1778)
						)
						(arc
							(start -0.2794 0.1778)
							(mid -0.249642 0.249642)
							(end -0.1778 0.2794)
						)
						(arc
							(start 0.1778 0.2794)
							(mid 0.249642 0.249642)
							(end 0.2794 0.1778)
						)
						(arc
							(start 0.2794 -0.1778)
							(mid 0.249642 -0.249642)
							(end 0.1778 -0.2794)
						)
					)
					(width 0)
					(fill yes)
				)
			)
		)
		(pad "2" smd custom
			(at 0 0.4445 90)
			(size 0.1397 0.1397)
			(layers "F.Cu" "F.Mask" "F.Paste")
			(net "FLT_HDD3")
			(options
				(clearance outline)
				(anchor circle)
			)
			(primitives
				(gr_poly
					(pts
						(arc
							(start -0.1778 -0.2794)
							(mid -0.249642 -0.249642)
							(end -0.2794 -0.1778)
						)
						(arc
							(start -0.2794 0.1778)
							(mid -0.249642 0.249642)
							(end -0.1778 0.2794)
						)
						(arc
							(start 0.1778 0.2794)
							(mid 0.249642 0.249642)
							(end 0.2794 0.1778)
						)
						(arc
							(start 0.2794 -0.1778)
							(mid 0.249642 -0.249642)
							(end 0.1778 -0.2794)
						)
					)
					(width 0)
					(fill yes)
				)
			)
		)
	)
	(footprint ""
		(layer "F.Cu")
		(at 84.581746 -188.2267 -90)
		(property "Reference" "R455"
			(at 0 0 270)
			(layer "F.SilkS")
			(hide yes)
			(effects
				(font
					(size 1.27 1.27)
				)
			)
		)
		(property "Value" "4K7R2J-2-GP"
			(at 0.064008 -3.993896 270)
			(unlocked yes)
			(layer "F.Fab")
			(hide yes)
			(effects
				(font
					(size 1.016 1.016)
					(thickness 0.1524)
				)
			)
		)
		(property "Device Type" "R402H16"
			(at 0.064008 -5.517896 270)
			(unlocked yes)
			(layer "F.Fab")
			(hide yes)
			(effects
				(font
					(size 1.016 1.016)
					(thickness 0.1524)
				)
			)
		)
		(duplicate_pad_numbers_are_jumpers no)
		(fp_line
			(start -0.508 -0.9398)
			(end -0.508 0.9398)
			(stroke
				(width 0.1524)
				(type default)
			)
			(layer "F.SilkS")
		)
		(fp_line
			(start 0.508 -0.9398)
			(end -0.508 -0.9398)
			(stroke
				(width 0.1524)
				(type default)
			)
			(layer "F.SilkS")
		)
		(fp_rect
			(start -0.508 0.9398)
			(end 0.508 -0.9398)
			(stroke
				(width 0)
				(type default)
			)
			(fill no)
			(layer "F.CrtYd")
		)
		(fp_rect
			(start -0.508 0.9398)
			(end 0.508 -0.9398)
			(stroke
				(width 0)
				(type default)
			)
			(fill no)
			(layer "F.Fab")
		)
		(pad "1" smd custom
			(at 0 -0.4445 270)
			(size 0.1397 0.1397)
			(layers "F.Cu" "F.Mask" "F.Paste")
			(net "P3V3")
			(options
				(clearance outline)
				(anchor circle)
			)
			(primitives
				(gr_poly
					(pts
						(arc
							(start -0.1778 -0.2794)
							(mid -0.249642 -0.249642)
							(end -0.2794 -0.1778)
						)
						(arc
							(start -0.2794 0.1778)
							(mid -0.249642 0.249642)
							(end -0.1778 0.2794)
						)
						(arc
							(start 0.1778 0.2794)
							(mid 0.249642 0.249642)
							(end 0.2794 0.1778)
						)
						(arc
							(start 0.2794 -0.1778)
							(mid 0.249642 -0.249642)
							(end 0.1778 -0.2794)
						)
					)
					(width 0)
					(fill yes)
				)
			)
		)
		(pad "2" smd custom
			(at 0 0.4445 270)
			(size 0.1397 0.1397)
			(layers "F.Cu" "F.Mask" "F.Paste")
			(net "SAS_EXP_B_PWR8")
			(options
				(clearance outline)
				(anchor circle)
			)
			(primitives
				(gr_poly
					(pts
						(arc
							(start -0.1778 -0.2794)
							(mid -0.249642 -0.249642)
							(end -0.2794 -0.1778)
						)
						(arc
							(start -0.2794 0.1778)
							(mid -0.249642 0.249642)
							(end -0.1778 0.2794)
						)
						(arc
							(start 0.1778 0.2794)
							(mid 0.249642 0.249642)
							(end 0.2794 0.1778)
						)
						(arc
							(start 0.2794 -0.1778)
							(mid 0.249642 -0.249642)
							(end 0.1778 -0.2794)
						)
					)
					(width 0)
					(fill yes)
				)
			)
		)
	)
	(footprint ""
		(layer "F.Cu")
		(at 79.304134 -494.006886 -90)
		(property "Reference" "R179"
			(at 0 0 270)
			(layer "F.SilkS")
			(hide yes)
			(effects
				(font
					(size 1.27 1.27)
				)
			)
		)
		(property "Value" "1KR2F-3-GP"
			(at 0.064008 -3.993896 270)
			(unlocked yes)
			(layer "F.Fab")
			(hide yes)
			(effects
				(font
					(size 1.016 1.016)
					(thickness 0.1524)
				)
			)
		)
		(property "Device Type" "R402H16"
			(at 0.064008 -5.517896 270)
			(unlocked yes)
			(layer "F.Fab")
			(hide yes)
			(effects
				(font
					(size 1.016 1.016)
					(thickness 0.1524)
				)
			)
		)
		(duplicate_pad_numbers_are_jumpers no)
		(fp_line
			(start -0.508 -0.9398)
			(end -0.508 0.9398)
			(stroke
				(width 0.1524)
				(type default)
			)
			(layer "F.SilkS")
		)
		(fp_line
			(start 0.508 -0.9398)
			(end -0.508 -0.9398)
			(stroke
				(width 0.1524)
				(type default)
			)
			(layer "F.SilkS")
		)
		(fp_rect
			(start -0.508 0.9398)
			(end 0.508 -0.9398)
			(stroke
				(width 0)
				(type default)
			)
			(fill no)
			(layer "F.CrtYd")
		)
		(fp_rect
			(start -0.508 0.9398)
			(end 0.508 -0.9398)
			(stroke
				(width 0)
				(type default)
			)
			(fill no)
			(layer "F.Fab")
		)
		(pad "1" smd custom
			(at 0 -0.4445 270)
			(size 0.1397 0.1397)
			(layers "F.Cu" "F.Mask" "F.Paste")
			(net "P3V3")
			(options
				(clearance outline)
				(anchor circle)
			)
			(primitives
				(gr_poly
					(pts
						(arc
							(start -0.1778 -0.2794)
							(mid -0.249642 -0.249642)
							(end -0.2794 -0.1778)
						)
						(arc
							(start -0.2794 0.1778)
							(mid -0.249642 0.249642)
							(end -0.1778 0.2794)
						)
						(arc
							(start 0.1778 0.2794)
							(mid 0.249642 0.249642)
							(end 0.2794 0.1778)
						)
						(arc
							(start 0.2794 -0.1778)
							(mid 0.249642 -0.249642)
							(end 0.1778 -0.2794)
						)
					)
					(width 0)
					(fill yes)
				)
			)
		)
		(pad "2" smd custom
			(at 0 0.4445 270)
			(size 0.1397 0.1397)
			(layers "F.Cu" "F.Mask" "F.Paste")
			(net "SW_PWR_HDD5")
			(options
				(clearance outline)
				(anchor circle)
			)
			(primitives
				(gr_poly
					(pts
						(arc
							(start -0.1778 -0.2794)
							(mid -0.249642 -0.249642)
							(end -0.2794 -0.1778)
						)
						(arc
							(start -0.2794 0.1778)
							(mid -0.249642 0.249642)
							(end -0.1778 0.2794)
						)
						(arc
							(start 0.1778 0.2794)
							(mid 0.249642 0.249642)
							(end 0.2794 0.1778)
						)
						(arc
							(start 0.2794 -0.1778)
							(mid 0.249642 -0.249642)
							(end 0.1778 -0.2794)
						)
					)
					(width 0)
					(fill yes)
				)
			)
		)
	)
	(footprint ""
		(layer "F.Cu")
		(at 71.500746 -393.2047)
		(property "Reference" "U19"
			(at 0 0 0)
			(layer "F.SilkS")
			(hide yes)
			(effects
				(font
					(size 1.27 1.27)
				)
			)
		)
		(property "Value" "74LVC1G08GW-1-GP"
			(at -2.3368 -8.6868 0)
			(unlocked yes)
			(layer "F.Fab")
			(hide yes)
			(effects
				(font
					(size 1.016 1.016)
					(thickness 0.1524)
				)
			)
		)
		(property "Device Type" "SC70-5H44"
			(at -2.3114 -10.414 0)
			(unlocked yes)
			(layer "F.Fab")
			(hide yes)
			(effects
				(font
					(size 1.016 1.016)
					(thickness 0.1524)
				)
			)
		)
		(duplicate_pad_numbers_are_jumpers no)
		(fp_line
			(start -1.27 -1.7018)
			(end 1.27 -1.7018)
			(stroke
				(width 0.1524)
				(type default)
			)
			(layer "F.SilkS")
		)
		(fp_line
			(start -1.27 1.7018)
			(end -1.27 -1.7018)
			(stroke
				(width 0.1524)
				(type default)
			)
			(layer "F.SilkS")
		)
		(fp_line
			(start 0.6604 -1.8034)
			(end 1.3843 -1.8034)
			(stroke
				(width 0.3302)
				(type default)
			)
			(layer "F.SilkS")
		)
		(fp_line
			(start 1.27 -1.7018)
			(end 1.27 1.7018)
			(stroke
				(width 0.1524)
				(type default)
			)
			(layer "F.SilkS")
		)
		(fp_line
			(start 1.27 1.7018)
			(end -1.27 1.7018)
			(stroke
				(width 0.1524)
				(type default)
			)
			(layer "F.SilkS")
		)
		(fp_line
			(start 1.3843 -1.8034)
			(end 1.3843 -1.1176)
			(stroke
				(width 0.3302)
				(type default)
			)
			(layer "F.SilkS")
		)
		(fp_rect
			(start -1.524 1.9558)
			(end 1.524 -1.9558)
			(stroke
				(width 0)
				(type default)
			)
			(fill no)
			(layer "F.CrtYd")
		)
		(fp_poly
			(pts
				(xy -1.524 -1.9558) (xy 1.524 -1.9558) (xy 1.524 1.9558) (xy -1.524 1.9558)
			)
			(stroke
				(width 0)
				(type default)
			)
			(fill no)
			(layer "F.Fab")
		)
		(pad "1" smd rect
			(at 0.65024 -0.8255)
			(size 0.4064 1.2192)
			(layers "F.Cu" "F.Mask" "F.Paste")
			(net "SAS2X28_B_HDD6_FLT")
		)
		(pad "2" smd rect
			(at 0 -0.8255)
			(size 0.4064 1.2192)
			(layers "F.Cu" "F.Mask" "F.Paste")
			(net "SAS2X28_A_HDD6_FLT")
		)
		(pad "3" smd rect
			(at -0.65024 -0.8255)
			(size 0.4064 1.2192)
			(layers "F.Cu" "F.Mask" "F.Paste")
			(net "GND")
		)
		(pad "4" smd rect
			(at -0.65024 0.8255)
			(size 0.4064 1.2192)
			(layers "F.Cu" "F.Mask" "F.Paste")
			(net "FLT_HDD6_DRIVE")
		)
		(pad "5" smd rect
			(at 0.65024 0.8255)
			(size 0.4064 1.2192)
			(layers "F.Cu" "F.Mask" "F.Paste")
			(net "P3V3")
		)
	)
	(footprint ""
		(layer "F.Cu")
		(at 92.202 -11.303)
		(property "Reference" "R577"
			(at 0 0 0)
			(layer "F.SilkS")
			(hide yes)
			(effects
				(font
					(size 1.27 1.27)
				)
			)
		)
		(property "Value" "300KR2F-GP"
			(at 0.064008 -3.993896 0)
			(unlocked yes)
			(layer "F.Fab")
			(hide yes)
			(effects
				(font
					(size 1.016 1.016)
					(thickness 0.1524)
				)
			)
		)
		(property "Device Type" "R402H16"
			(at 0.064008 -5.517896 0)
			(unlocked yes)
			(layer "F.Fab")
			(hide yes)
			(effects
				(font
					(size 1.016 1.016)
					(thickness 0.1524)
				)
			)
		)
		(duplicate_pad_numbers_are_jumpers no)
		(fp_line
			(start -0.508 -0.9398)
			(end -0.508 0.9398)
			(stroke
				(width 0.1524)
				(type default)
			)
			(layer "F.SilkS")
		)
		(fp_line
			(start 0.508 -0.9398)
			(end -0.508 -0.9398)
			(stroke
				(width 0.1524)
				(type default)
			)
			(layer "F.SilkS")
		)
		(fp_rect
			(start -0.508 0.9398)
			(end 0.508 -0.9398)
			(stroke
				(width 0)
				(type default)
			)
			(fill no)
			(layer "F.CrtYd")
		)
		(fp_rect
			(start -0.508 0.9398)
			(end 0.508 -0.9398)
			(stroke
				(width 0)
				(type default)
			)
			(fill no)
			(layer "F.Fab")
		)
		(pad "1" smd custom
			(at 0 -0.4445)
			(size 0.1397 0.1397)
			(layers "F.Cu" "F.Mask" "F.Paste")
			(net "SW_HDD14_N")
			(options
				(clearance outline)
				(anchor circle)
			)
			(primitives
				(gr_poly
					(pts
						(arc
							(start -0.1778 -0.2794)
							(mid -0.249642 -0.249642)
							(end -0.2794 -0.1778)
						)
						(arc
							(start -0.2794 0.1778)
							(mid -0.249642 0.249642)
							(end -0.1778 0.2794)
						)
						(arc
							(start 0.1778 0.2794)
							(mid 0.249642 0.249642)
							(end 0.2794 0.1778)
						)
						(arc
							(start 0.2794 -0.1778)
							(mid 0.249642 -0.249642)
							(end 0.1778 -0.2794)
						)
					)
					(width 0)
					(fill yes)
				)
			)
		)
		(pad "2" smd custom
			(at 0 0.4445)
			(size 0.1397 0.1397)
			(layers "F.Cu" "F.Mask" "F.Paste")
			(net "P12V")
			(options
				(clearance outline)
				(anchor circle)
			)
			(primitives
				(gr_poly
					(pts
						(arc
							(start -0.1778 -0.2794)
							(mid -0.249642 -0.249642)
							(end -0.2794 -0.1778)
						)
						(arc
							(start -0.2794 0.1778)
							(mid -0.249642 0.249642)
							(end -0.1778 0.2794)
						)
						(arc
							(start 0.1778 0.2794)
							(mid 0.249642 0.249642)
							(end 0.2794 0.1778)
						)
						(arc
							(start 0.2794 -0.1778)
							(mid 0.249642 -0.249642)
							(end 0.1778 -0.2794)
						)
					)
					(width 0)
					(fill yes)
				)
			)
		)
	)
	(footprint ""
		(layer "F.Cu")
		(at 230.267256 -453.545702 90)
		(property "Reference" "R101"
			(at 0 0 90)
			(layer "F.SilkS")
			(hide yes)
			(effects
				(font
					(size 1.27 1.27)
				)
			)
		)
		(property "Value" "10KR2F-2-GP"
			(at 0.064008 -3.993896 90)
			(unlocked yes)
			(layer "F.Fab")
			(hide yes)
			(effects
				(font
					(size 1.016 1.016)
					(thickness 0.1524)
				)
			)
		)
		(property "Device Type" "R402H16"
			(at 0.064008 -5.517896 90)
			(unlocked yes)
			(layer "F.Fab")
			(hide yes)
			(effects
				(font
					(size 1.016 1.016)
					(thickness 0.1524)
				)
			)
		)
		(duplicate_pad_numbers_are_jumpers no)
		(fp_line
			(start 0.508 -0.9398)
			(end -0.508 -0.9398)
			(stroke
				(width 0.1524)
				(type default)
			)
			(layer "F.SilkS")
		)
		(fp_line
			(start -0.508 -0.9398)
			(end -0.508 0.9398)
			(stroke
				(width 0.1524)
				(type default)
			)
			(layer "F.SilkS")
		)
		(fp_rect
			(start -0.508 0.9398)
			(end 0.508 -0.9398)
			(stroke
				(width 0)
				(type default)
			)
			(fill no)
			(layer "F.CrtYd")
		)
		(fp_rect
			(start -0.508 0.9398)
			(end 0.508 -0.9398)
			(stroke
				(width 0)
				(type default)
			)
			(fill no)
			(layer "F.Fab")
		)
		(pad "1" smd custom
			(at 0 -0.4445 90)
			(size 0.1397 0.1397)
			(layers "F.Cu" "F.Mask" "F.Paste")
			(net "P5VA")
			(options
				(clearance outline)
				(anchor circle)
			)
			(primitives
				(gr_poly
					(pts
						(arc
							(start -0.1778 -0.2794)
							(mid -0.249642 -0.249642)
							(end -0.2794 -0.1778)
						)
						(arc
							(start -0.2794 0.1778)
							(mid -0.249642 0.249642)
							(end -0.1778 0.2794)
						)
						(arc
							(start 0.1778 0.2794)
							(mid 0.249642 0.249642)
							(end 0.2794 0.1778)
						)
						(arc
							(start 0.2794 -0.1778)
							(mid 0.249642 -0.249642)
							(end 0.1778 -0.2794)
						)
					)
					(width 0)
					(fill yes)
				)
			)
		)
		(pad "2" smd custom
			(at 0 0.4445 90)
			(size 0.1397 0.1397)
			(layers "F.Cu" "F.Mask" "F.Paste")
			(net "DRIVE_ACT_0")
			(options
				(clearance outline)
				(anchor circle)
			)
			(primitives
				(gr_poly
					(pts
						(arc
							(start -0.1778 -0.2794)
							(mid -0.249642 -0.249642)
							(end -0.2794 -0.1778)
						)
						(arc
							(start -0.2794 0.1778)
							(mid -0.249642 0.249642)
							(end -0.1778 0.2794)
						)
						(arc
							(start 0.1778 0.2794)
							(mid 0.249642 0.249642)
							(end 0.2794 0.1778)
						)
						(arc
							(start 0.2794 -0.1778)
							(mid 0.249642 -0.249642)
							(end 0.1778 -0.2794)
						)
					)
					(width 0)
					(fill yes)
				)
			)
		)
	)
	(footprint ""
		(layer "F.Cu")
		(at 60.832746 -25.9207 90)
		(property "Reference" "PG2"
			(at 0 0 90)
			(layer "F.SilkS")
			(hide yes)
			(effects
				(font
					(size 1.27 1.27)
				)
			)
		)
		(property "Value" "COPPER-CLOSE-GP-U"
			(at 0.0762 -2.8702 90)
			(unlocked yes)
			(layer "F.Fab")
			(hide yes)
			(effects
				(font
					(size 1.016 1.016)
					(thickness 0.1524)
				)
			)
		)
		(property "Device Type" "CON2C-U"
			(at 0.0762 -4.3942 90)
			(unlocked yes)
			(layer "F.Fab")
			(hide yes)
			(effects
				(font
					(size 1.016 1.016)
					(thickness 0.1524)
				)
			)
		)
		(duplicate_pad_numbers_are_jumpers no)
		(fp_rect
			(start -0.9398 0.9652)
			(end 0.9398 -0.9652)
			(stroke
				(width 0)
				(type default)
			)
			(fill no)
			(layer "F.CrtYd")
		)
		(fp_rect
			(start -0.9398 0.9652)
			(end 0.9398 -0.9652)
			(stroke
				(width 0)
				(type default)
			)
			(fill no)
			(layer "F.Fab")
		)
		(pad "1" smd custom
			(at 0 -0.5334 90)
			(size 0.17145 0.17145)
			(layers "F.Cu" "F.Mask" "F.Paste")
			(net "P5VB_AGND")
			(options
				(clearance outline)
				(anchor circle)
			)
			(primitives
				(gr_poly
					(pts
						(xy -0.127 0.3429) (xy -0.127 0.1651) (xy -0.635 -0.3429) (xy 0.635 -0.3429) (xy 0.127 0.1651)
						(xy 0.127 0.3429)
					)
					(width 0)
					(fill yes)
				)
			)
		)
		(pad "2" smd custom
			(at 0 0.5334 90)
			(size 0.17145 0.17145)
			(layers "F.Cu" "F.Mask" "F.Paste")
			(net "GND")
			(options
				(clearance outline)
				(anchor circle)
			)
			(primitives
				(gr_poly
					(pts
						(xy -0.635 0.3429) (xy -0.127 -0.1651) (xy -0.127 -0.3429) (xy 0.127 -0.3429) (xy 0.127 -0.1651)
						(xy 0.635 0.3429)
					)
					(width 0)
					(fill yes)
				)
			)
		)
	)
)
